(kicad_pcb
	(version 20221018)
	(generator pcbnew)
	(general
    (thickness 1.62)
  )
	(paper "A4")
	(title_block
    (title "ECP5 - Datacenter Secure Control Module (DC-SCM)")
    (date "2024-07-01")
    (rev "1.2.1")
		(comment 9 "footprints 81-84 of 506")
	)
	(layers
    (0 "F.Cu" signal)
    (1 "In1.Cu" power)
    (2 "In2.Cu" signal)
    (3 "In3.Cu" power)
    (4 "In4.Cu" power)
    (5 "In5.Cu" signal)
    (6 "In6.Cu" power)
    (31 "B.Cu" signal)
    (32 "B.Adhes" user "B.Adhesive")
    (33 "F.Adhes" user "F.Adhesive")
    (34 "B.Paste" user)
    (35 "F.Paste" user)
    (36 "B.SilkS" user "B.Silkscreen")
    (37 "F.SilkS" user "F.Silkscreen")
    (38 "B.Mask" user)
    (39 "F.Mask" user)
    (40 "Dwgs.User" user "User.Drawings")
    (41 "Cmts.User" user "User.Comments")
    (42 "Eco1.User" user "User.Eco1")
    (43 "Eco2.User" user "User.Eco2")
    (44 "Edge.Cuts" user)
    (45 "Margin" user)
    (46 "B.CrtYd" user "B.Courtyard")
    (47 "F.CrtYd" user "F.Courtyard")
    (48 "B.Fab" user)
    (49 "F.Fab" user)
  )
	(footprint "antmicro-footprints:LED_0603_1608Metric_G" (layer "F.Cu")
    (at 140.9 168.3)
    (descr "LED SMD 0603 Green")
    (tags "LED SMD 0603 Green")
    (property "Author" "Antmicro")
    (property "Color" "Green")
    (property "License" "Apache-2.0")
    (property "MPN" "LG L29K-G2J1-24-Z")
    (property "Manufacturer" "OSRAM")
    (property "Sheetfile" "pcie-conn.kicad_sch")
    (property "Sheetname" "PCIe-connector")
    (property "ki_description" "LED, Green, SMD, 0603, 20 mA, 1.7 V, 570 nm")
    (property "ki_keywords" "SMT, DIODE, SEMICONDUCTOR, LED")
    (attr smd)
    (fp_text reference "D1" (at 0.78 -1.245) (layer "F.SilkS")
        (effects (font (size 0.7 0.7) (thickness 0.127)))
    )
    (fp_text value "LED_G_0603_LG_L29K-G2J1-24-Z" (at 0 1.77) (layer "F.Fab")
        (effects (font (size 1 1) (thickness 0.15)))
    )
    (fp_text user "License: Apache-2.0" (at -1.4224 3.599) (layer "F.Fab") hide
        (effects (font (size 0.7 0.7) (thickness 0.15)) (justify left bottom))
    )
    (fp_text user "${REFERENCE}" (at -1.4224 5.999) (layer "F.Fab") hide
        (effects (font (size 0.7 0.7) (thickness 0.15)) (justify left bottom))
    )
    (fp_text user "Author: Antmicro" (at -1.4224 4.799) (layer "F.Fab") hide
        (effects (font (size 0.7 0.7) (thickness 0.15)) (justify left bottom))
    )
    (fp_line (start -1.18 -0.319) (end -1.18 0.321)
      (stroke (width 0.15) (type solid)) (layer "F.SilkS"))
    (fp_line (start -0.094672 0.001008) (end -0.24 0.001008)
      (stroke (width 0.1) (type solid)) (layer "F.SilkS"))
    (fp_line (start -0.094672 0.001008) (end 0.105328 -0.198992)
      (stroke (width 0.1) (type solid)) (layer "F.SilkS"))
    (fp_line (start -0.094672 0.201008) (end -0.094672 -0.198992)
      (stroke (width 0.1) (type solid)) (layer "F.SilkS"))
    (fp_line (start 0.105328 0.001008) (end 0.24 0.001)
      (stroke (width 0.1) (type solid)) (layer "F.SilkS"))
    (fp_line (start 0.105328 0.201008) (end -0.094672 0.001008)
      (stroke (width 0.1) (type solid)) (layer "F.SilkS"))
    (fp_line (start 0.105328 0.201008) (end 0.105328 -0.198992)
      (stroke (width 0.1) (type solid)) (layer "F.SilkS"))
    (fp_line (start 0.22 -0.35) (end -0.22 -0.35)
      (stroke (width 0.15) (type solid)) (layer "F.SilkS"))
    (fp_line (start 0.22 0.35) (end -0.22 0.35)
      (stroke (width 0.15) (type solid)) (layer "F.SilkS"))
    (fp_rect (start 1.25 0.65) (end -1.25 -0.65)
      (stroke (width 0.05) (type solid)) (fill none) (layer "F.CrtYd"))
    (fp_line (start -0.199 -0.202) (end -0.199 0.1)
      (stroke (width 0.15) (type solid)) (layer "F.Fab"))
    (fp_line (start -0.199 0) (end -0.597 0)
      (stroke (width 0.15) (type solid)) (layer "F.Fab"))
    (fp_line (start -0.199 0.2) (end -0.199 0.1)
      (stroke (width 0.15) (type solid)) (layer "F.Fab"))
    (fp_line (start -0.101 0) (end 0.201 0.2)
      (stroke (width 0.15) (type solid)) (layer "F.Fab"))
    (fp_line (start 0.201 -0.202) (end -0.101 0)
      (stroke (width 0.15) (type solid)) (layer "F.Fab"))
    (fp_line (start 0.201 0) (end 0.201 -0.202)
      (stroke (width 0.15) (type solid)) (layer "F.Fab"))
    (fp_line (start 0.201 0.2) (end 0.201 0)
      (stroke (width 0.15) (type solid)) (layer "F.Fab"))
    (fp_line (start 0.599 0) (end 0.201 0)
      (stroke (width 0.15) (type solid)) (layer "F.Fab"))
    (fp_rect (start 0.848 0.4) (end -0.85 -0.402)
      (stroke (width 0.15) (type solid)) (fill none) (layer "F.Fab"))
    (pad "1" smd roundrect (at -0.7 0 180) (size 0.8 1) (layers "F.Cu" "F.Paste" "F.Mask") (roundrect_rratio 0.2)
      (net 308 "Net-(D1-C)") (pinfunction "C") (pintype "passive"))
    (pad "2" smd roundrect (at 0.7 0 180) (size 0.8 1) (layers "F.Cu" "F.Paste" "F.Mask") (roundrect_rratio 0.2)
      (net 777 "Net-(D1-A)") (pinfunction "A") (pintype "passive"))
  )
	(footprint "antmicro-footprints:SOIC-8_5.3x5.3x2mm_P1.27mm" (layer "F.Cu")
    (at 68.245 134.11)
    (descr "8-Pin SOIC 208-mil")
    (property "Author" "Antmicro")
    (property "License" "Apache-2.0")
    (property "MPN" "W25Q32JVSSIQ")
    (property "Manufacturer" "Winbond")
    (property "Sheetfile" "rot.kicad_sch")
    (property "Sheetname" "RoT")
    (property "ki_description" "Flash Memory, Serial NOR, 32 Mbit, 4M x 8bit, SPI, SOIC, 8 Pins")
    (property "ki_keywords" "FLASH, SPI, MEMORY")
    (attr smd)
    (fp_text reference "U4" (at -0.0015 -3.2) (layer "F.SilkS")
        (effects (font (size 0.7 0.7) (thickness 0.15)) (justify left bottom))
    )
    (fp_text value "W25Q32JVSSIQ" (at 0 3.8) (layer "F.Fab")
        (effects (font (size 0.7 0.7) (thickness 0.15)) (justify left bottom))
    )
    (fp_text user "License: Apache-2.0" (at -4.675 6.938) (layer "F.Fab") hide
        (effects (font (size 0.7 0.7) (thickness 0.15)) (justify left bottom))
    )
    (fp_text user "Author: Antmicro" (at -4.675 5.938) (layer "F.Fab") hide
        (effects (font (size 0.7 0.7) (thickness 0.15)) (justify left bottom))
    )
    (fp_text user "${REFERENCE}" (at -4.675 4.938) (layer "F.Fab") hide
        (effects (font (size 0.7 0.7) (thickness 0.15)) (justify left bottom))
    )
    (fp_line (start -2.8 -2.641) (end -4.4 -2.641)
      (stroke (width 0.15) (type solid)) (layer "F.SilkS"))
    (fp_circle (center -4.85 -1.905) (end -4.8 -1.855)
      (stroke (width 0.15) (type solid)) (fill solid) (layer "F.SilkS"))
    (fp_rect (start 4.675 -3) (end -4.675 3)
      (stroke (width 0.05) (type solid)) (fill none) (layer "F.CrtYd"))
    (fp_line (start -2.641 -2.641) (end 2.64 -2.641)
      (stroke (width 0.15) (type solid)) (layer "F.Fab"))
    (fp_line (start -2.641 -1.371) (end -1.371 -2.641)
      (stroke (width 0.15) (type solid)) (layer "F.Fab"))
    (fp_line (start -2.641 2.64) (end -2.641 -2.641)
      (stroke (width 0.15) (type solid)) (layer "F.Fab"))
    (fp_line (start 2.64 -2.641) (end 2.64 2.64)
      (stroke (width 0.15) (type solid)) (layer "F.Fab"))
    (fp_line (start 2.64 2.64) (end -2.641 2.64)
      (stroke (width 0.15) (type solid)) (layer "F.Fab"))
    (pad "1" smd roundrect (at -3.601 -1.905 90) (size 0.65 1.65) (layers "F.Cu" "F.Paste" "F.Mask") (roundrect_rratio 0.25)
      (net 145 "QSPIA2_CS_N") (pinfunction "~{CS}") (pintype "input"))
    (pad "2" smd roundrect (at -3.601 -0.635 90) (size 0.65 1.65) (layers "F.Cu" "F.Paste" "F.Mask") (roundrect_rratio 0.25)
      (net 142 "QSPIA2_D1") (pinfunction "SO/IO1") (pintype "bidirectional"))
    (pad "3" smd roundrect (at -3.601 0.633 90) (size 0.65 1.65) (layers "F.Cu" "F.Paste" "F.Mask") (roundrect_rratio 0.25)
      (net 143 "QSPIA2_D2") (pinfunction "~{WP}/IO2") (pintype "bidirectional"))
    (pad "4" smd roundrect (at -3.601 1.904 90) (size 0.65 1.65) (layers "F.Cu" "F.Paste" "F.Mask") (roundrect_rratio 0.25)
      (net 1 "GND") (pinfunction "VSS") (pintype "power_in"))
    (pad "5" smd roundrect (at 3.6 1.904 90) (size 0.65 1.65) (layers "F.Cu" "F.Paste" "F.Mask") (roundrect_rratio 0.25)
      (net 141 "QSPIA2_D0") (pinfunction "SI/IO0") (pintype "bidirectional"))
    (pad "6" smd roundrect (at 3.6 0.633 90) (size 0.65 1.65) (layers "F.Cu" "F.Paste" "F.Mask") (roundrect_rratio 0.25)
      (net 135 "QSPIA_CLK") (pinfunction "SCLK") (pintype "input"))
    (pad "7" smd roundrect (at 3.6 -0.635 90) (size 0.65 1.65) (layers "F.Cu" "F.Paste" "F.Mask") (roundrect_rratio 0.25)
      (net 144 "QSPIA2_D3") (pinfunction "~{HOLD}/IO3") (pintype "bidirectional"))
    (pad "8" smd roundrect (at 3.6 -1.905 90) (size 0.65 1.65) (layers "F.Cu" "F.Paste" "F.Mask") (roundrect_rratio 0.25)
      (net 2 "VCC3V3") (pinfunction "VCC") (pintype "power_in"))
  )
	(footprint "antmicro-footprints:SOIC-8_5.3x5.3x2mm_P1.27mm" (layer "F.Cu")
    (at 68.245 143.01)
    (descr "8-Pin SOIC 208-mil")
    (property "Author" "Antmicro")
    (property "License" "Apache-2.0")
    (property "MPN" "W25Q32JVSSIQ")
    (property "Manufacturer" "Winbond")
    (property "Sheetfile" "rot.kicad_sch")
    (property "Sheetname" "RoT")
    (property "ki_description" "Flash Memory, Serial NOR, 32 Mbit, 4M x 8bit, SPI, SOIC, 8 Pins")
    (property "ki_keywords" "FLASH, SPI, MEMORY")
    (attr smd)
    (fp_text reference "U5" (at -0.0015 -3.2) (layer "F.SilkS")
        (effects (font (size 0.7 0.7) (thickness 0.15)) (justify left bottom))
    )
    (fp_text value "W25Q32JVSSIQ" (at 0 3.8) (layer "F.Fab")
        (effects (font (size 0.7 0.7) (thickness 0.15)) (justify left bottom))
    )
    (fp_text user "${REFERENCE}" (at -4.675 4.938) (layer "F.Fab") hide
        (effects (font (size 0.7 0.7) (thickness 0.15)) (justify left bottom))
    )
    (fp_text user "License: Apache-2.0" (at -4.675 6.938) (layer "F.Fab") hide
        (effects (font (size 0.7 0.7) (thickness 0.15)) (justify left bottom))
    )
    (fp_text user "Author: Antmicro" (at -4.675 5.938) (layer "F.Fab") hide
        (effects (font (size 0.7 0.7) (thickness 0.15)) (justify left bottom))
    )
    (fp_line (start -2.8 -2.641) (end -4.4 -2.641)
      (stroke (width 0.15) (type solid)) (layer "F.SilkS"))
    (fp_circle (center -4.85 -1.905) (end -4.8 -1.855)
      (stroke (width 0.15) (type solid)) (fill solid) (layer "F.SilkS"))
    (fp_rect (start 4.675 -3) (end -4.675 3)
      (stroke (width 0.05) (type solid)) (fill none) (layer "F.CrtYd"))
    (fp_line (start -2.641 -2.641) (end 2.64 -2.641)
      (stroke (width 0.15) (type solid)) (layer "F.Fab"))
    (fp_line (start -2.641 -1.371) (end -1.371 -2.641)
      (stroke (width 0.15) (type solid)) (layer "F.Fab"))
    (fp_line (start -2.641 2.64) (end -2.641 -2.641)
      (stroke (width 0.15) (type solid)) (layer "F.Fab"))
    (fp_line (start 2.64 -2.641) (end 2.64 2.64)
      (stroke (width 0.15) (type solid)) (layer "F.Fab"))
    (fp_line (start 2.64 2.64) (end -2.641 2.64)
      (stroke (width 0.15) (type solid)) (layer "F.Fab"))
    (pad "1" smd roundrect (at -3.601 -1.905 90) (size 0.65 1.65) (layers "F.Cu" "F.Paste" "F.Mask") (roundrect_rratio 0.25)
      (net 140 "QSPIA1_CS_N") (pinfunction "~{CS}") (pintype "input"))
    (pad "2" smd roundrect (at -3.601 -0.635 90) (size 0.65 1.65) (layers "F.Cu" "F.Paste" "F.Mask") (roundrect_rratio 0.25)
      (net 137 "QSPIA1_D1") (pinfunction "SO/IO1") (pintype "bidirectional"))
    (pad "3" smd roundrect (at -3.601 0.633 90) (size 0.65 1.65) (layers "F.Cu" "F.Paste" "F.Mask") (roundrect_rratio 0.25)
      (net 138 "QSPIA1_D2") (pinfunction "~{WP}/IO2") (pintype "bidirectional"))
    (pad "4" smd roundrect (at -3.601 1.904 90) (size 0.65 1.65) (layers "F.Cu" "F.Paste" "F.Mask") (roundrect_rratio 0.25)
      (net 1 "GND") (pinfunction "VSS") (pintype "power_in"))
    (pad "5" smd roundrect (at 3.6 1.904 90) (size 0.65 1.65) (layers "F.Cu" "F.Paste" "F.Mask") (roundrect_rratio 0.25)
      (net 136 "QSPIA1_D0") (pinfunction "SI/IO0") (pintype "bidirectional"))
    (pad "6" smd roundrect (at 3.6 0.633 90) (size 0.65 1.65) (layers "F.Cu" "F.Paste" "F.Mask") (roundrect_rratio 0.25)
      (net 135 "QSPIA_CLK") (pinfunction "SCLK") (pintype "input"))
    (pad "7" smd roundrect (at 3.6 -0.635 90) (size 0.65 1.65) (layers "F.Cu" "F.Paste" "F.Mask") (roundrect_rratio 0.25)
      (net 139 "QSPIA1_D3") (pinfunction "~{HOLD}/IO3") (pintype "bidirectional"))
    (pad "8" smd roundrect (at 3.6 -1.905 90) (size 0.65 1.65) (layers "F.Cu" "F.Paste" "F.Mask") (roundrect_rratio 0.25)
      (net 2 "VCC3V3") (pinfunction "VCC") (pintype "power_in"))
  )
	(footprint "antmicro-footprints:RJ45_BEL_L834-1G1T-S7" (layer "F.Cu")
    (at 99.955 80.845 180)
    (property "Author" "Antmicro")
    (property "License" "Apache-2.0")
    (property "MPN" "L834-1G1T-S7")
    (property "Manufacturer" "Bel Fuse")
    (property "Sheetfile" "ethernet.kicad_sch")
    (property "Sheetname" "Ethernet")
    (property "ki_description" "Modular connector with magnetics")
    (property "ki_keywords" "HORIZONTAL, THT, FILTERED, CONNECTOR, ETHERNET")
    (attr through_hole)
    (fp_text reference "J1" (at 6.97 -12.09) (layer "F.SilkS")
        (effects (font (size 0.7 0.7) (thickness 0.127)))
    )
    (fp_text value "L834-1G1T-S7" (at 2.16 -12.635) (layer "F.Fab")
        (effects (font (size 1 1) (thickness 0.015)))
    )
    (fp_text user "Author: Antmicro" (at -15.042 25.39 180) (layer "F.Fab") hide
        (effects (font (size 0.7 0.7) (thickness 0.15)) (justify left bottom))
    )
    (fp_text user "${REFERENCE}" (at -15.042 24.19 180) (layer "F.Fab") hide
        (effects (font (size 0.7 0.7) (thickness 0.15)) (justify left bottom))
    )
    (fp_text user "License: Apache-2.0" (at -15.042 26.589 180) (layer "F.Fab") hide
        (effects (font (size 0.7 0.7) (thickness 0.15)) (justify left bottom))
    )
    (fp_line (start -13.34 -4.121) (end -13.34 -0.471)
      (stroke (width 0.15) (type solid)) (layer "F.SilkS"))
    (fp_line (start -13.34 2.53) (end -13.34 3.93)
      (stroke (width 0.15) (type solid)) (layer "F.SilkS"))
    (fp_line (start -13.34 10.13) (end -13.34 18.158)
      (stroke (width 0.15) (type solid)) (layer "F.SilkS"))
    (fp_line (start 3.179 -4.121) (end -13.34 -4.121)
      (stroke (width 0.15) (type solid)) (layer "F.SilkS"))
    (fp_line (start 3.179 -4.121) (end 3.179 1.929)
      (stroke (width 0.15) (type solid)) (layer "F.SilkS"))
    (fp_line (start 3.179 8.13) (end 3.179 9.529)
      (stroke (width 0.15) (type solid)) (layer "F.SilkS"))
    (fp_line (start 3.179 12.53) (end 3.179 18.158)
      (stroke (width 0.15) (type solid)) (layer "F.SilkS"))
    (fp_line (start -15.06 22.19) (end -15.06 -0.3)
      (stroke (width 0.05) (type solid)) (layer "F.CrtYd"))
    (fp_line (start -13.6 -4.4) (end 3.5 -4.4)
      (stroke (width 0.05) (type solid)) (layer "F.CrtYd"))
    (fp_line (start -13.6 -0.3) (end -15.06 -0.3)
      (stroke (width 0.05) (type solid)) (layer "F.CrtYd"))
    (fp_line (start -13.6 -0.3) (end -13.6 -4.4)
      (stroke (width 0.05) (type solid)) (layer "F.CrtYd"))
    (fp_line (start 3.5 -0.3) (end 3.5 -4.4)
      (stroke (width 0.05) (type solid)) (layer "F.CrtYd"))
    (fp_line (start 4.87 -0.3) (end 3.5 -0.3)
      (stroke (width 0.05) (type solid)) (layer "F.CrtYd"))
    (fp_line (start 4.87 -0.3) (end 4.87 22.19)
      (stroke (width 0.05) (type solid)) (layer "F.CrtYd"))
    (fp_line (start 4.87 22.19) (end -15.06 22.19)
      (stroke (width 0.05) (type solid)) (layer "F.CrtYd"))
    (fp_line (start -13.34 -4.121) (end -13.34 21.94)
      (stroke (width 0.15) (type solid)) (layer "F.Fab"))
    (fp_line (start -13.34 21.94) (end 3.179 21.94)
      (stroke (width 0.15) (type solid)) (layer "F.Fab"))
    (fp_line (start 3.179 -4.121) (end -13.34 -4.121)
      (stroke (width 0.15) (type solid)) (layer "F.Fab"))
    (fp_line (start 3.179 21.94) (end 3.179 -4.121)
      (stroke (width 0.15) (type solid)) (layer "F.Fab"))
    (fp_arc (start -13.34 21.94) (mid -14.551 18.158) (end -14.74 14.192)
      (stroke (width 0.15) (type solid)) (layer "F.Fab"))
    (fp_arc (start 4.578 14.192) (mid 4.389 18.158) (end 3.179 21.94)
      (stroke (width 0.15) (type solid)) (layer "F.Fab"))
    (pad "" np_thru_hole circle (at -13.235 1.009 180) (size 2.31 2.31) (drill 2.31) (layers "*.Cu" "*.Mask"))
    (pad "" np_thru_hole circle (at -13.235 8.63 180) (size 2.31 2.31) (drill 2.31) (layers "*.Cu" "*.Mask"))
    (pad "" np_thru_hole circle (at 3.073 3.43 180) (size 2.31 2.31) (drill 2.31) (layers "*.Cu" "*.Mask"))
    (pad "" np_thru_hole circle (at 3.073 11.047 180) (size 2.31 2.31) (drill 2.31) (layers "*.Cu" "*.Mask"))
    (pad "1" thru_hole rect (at 0 0 180) (size 1.53 1.53) (drill 1.02) (layers "*.Cu" "*.Mask")
      (net 13 "Net-(J1-TRCT3)") (pinfunction "TRCT3") (pintype "passive"))
    (pad "2" thru_hole circle (at -2.032 0 180) (size 1.53 1.53) (drill 1.02) (layers "*.Cu" "*.Mask")
      (net 152 "/Ethernet/ETH3_N") (pinfunction "TRD3-") (pintype "passive"))
    (pad "3" thru_hole circle (at -4.064 0 180) (size 1.53 1.53) (drill 1.02) (layers "*.Cu" "*.Mask")
      (net 146 "/Ethernet/ETH3_P") (pinfunction "TRD3+") (pintype "passive"))
    (pad "4" thru_hole circle (at -6.096 0 180) (size 1.53 1.53) (drill 1.02) (layers "*.Cu" "*.Mask")
      (net 147 "/Ethernet/ETH2_P") (pinfunction "TRD2+") (pintype "passive"))
    (pad "5" thru_hole circle (at -8.128 0 180) (size 1.53 1.53) (drill 1.02) (layers "*.Cu" "*.Mask")
      (net 150 "/Ethernet/ETH2_N") (pinfunction "TRD2-") (pintype "passive"))
    (pad "6" thru_hole circle (at -10.16 0 180) (size 1.53 1.53) (drill 1.02) (layers "*.Cu" "*.Mask")
      (net 8 "Net-(J1-TRCT2)") (pinfunction "TRCT2") (pintype "passive"))
    (pad "7" thru_hole circle (at 1.015 -2.54 180) (size 1.53 1.53) (drill 1.02) (layers "*.Cu" "*.Mask")
      (net 14 "Net-(J1-TRCT4)") (pinfunction "TRCT4") (pintype "passive"))
    (pad "8" thru_hole circle (at -1.016 -2.54 180) (size 1.53 1.53) (drill 1.02) (layers "*.Cu" "*.Mask")
      (net 149 "/Ethernet/ETH4_P") (pinfunction "TRD4+") (pintype "passive"))
    (pad "9" thru_hole circle (at -3.048 -2.54 180) (size 1.53 1.53) (drill 1.02) (layers "*.Cu" "*.Mask")
      (net 153 "/Ethernet/ETH4_N") (pinfunction "TRD4-") (pintype "passive"))
    (pad "10" thru_hole circle (at -7.112 -2.54 180) (size 1.53 1.53) (drill 1.02) (layers "*.Cu" "*.Mask")
      (net 151 "/Ethernet/ETH1_N") (pinfunction "TRD1-") (pintype "passive"))
    (pad "11" thru_hole circle (at -9.144 -2.54 180) (size 1.53 1.53) (drill 1.02) (layers "*.Cu" "*.Mask")
      (net 148 "/Ethernet/ETH1_P") (pinfunction "TRD1+") (pintype "passive"))
    (pad "12" thru_hole circle (at -11.176 -2.54 180) (size 1.53 1.53) (drill 1.02) (layers "*.Cu" "*.Mask")
      (net 7 "Net-(J1-TRCT1)") (pinfunction "TRCT1") (pintype "passive"))
    (pad "13" thru_hole circle (at 1.945 13.97 180) (size 1.725 1.725) (drill 1.15) (layers "*.Cu" "*.Mask")
      (net 680 "Net-(J1-Pad13)") (pintype "passive"))
    (pad "14" thru_hole circle (at 1.945 16.508 180) (size 1.725 1.725) (drill 1.15) (layers "*.Cu" "*.Mask")
      (net 2 "VCC3V3") (pintype "passive"))
    (pad "15" thru_hole circle (at -12.106 13.97 180) (size 1.725 1.725) (drill 1.15) (layers "*.Cu" "*.Mask")
      (net 681 "Net-(J1-Pad15)") (pintype "passive"))
    (pad "16" thru_hole circle (at -12.106 16.508 180) (size 1.725 1.725) (drill 1.15) (layers "*.Cu" "*.Mask")
      (net 2 "VCC3V3") (pintype "passive"))
    (pad "SH" thru_hole circle (at -13.235 5.328 180) (size 2.1 2.1) (drill 1.4) (layers "*.Cu" "*.Mask")
      (net 1 "GND") (pinfunction "SH") (pintype "passive"))
    (pad "SH" thru_hole circle (at 3.073 6.73 180) (size 2.1 2.1) (drill 1.4) (layers "*.Cu" "*.Mask")
      (net 1 "GND") (pinfunction "SH") (pintype "passive"))
  )
)
